(kicad_pcb
	(version 20260206)
	(generator "pcbnew")
	(generator_version "10.0")
	(general
		(thickness 1.6)
		(legacy_teardrops no)
	)
	(paper "A4")
	(title_block
		(title "Bryce Canyon_R.DPB_16317-1_OCP.brd")
		(comment 1 "Bryce Canyon / footprints 66-72 of 2099")
	)
	(layers
		(0 "F.Cu" signal "TOP")
		(4 "In1.Cu" signal "L2GND")
		(6 "In2.Cu" signal "L3")
		(8 "In3.Cu" signal "L4VCC")
		(10 "In4.Cu" signal "L5VCC")
		(12 "In5.Cu" signal "L6")
		(14 "In6.Cu" signal "L7GND")
		(2 "B.Cu" signal "BOTTOM")
		(9 "F.Adhes" user "F.Adhesive")
		(11 "B.Adhes" user "B.Adhesive")
		(13 "F.Paste" user "Package Geometry/Pastemask Top")
		(15 "B.Paste" user "Package Geometry/Pastemask Bottom")
		(5 "F.SilkS" user "Ref Des/Silkscreen Top")
		(7 "B.SilkS" user "Ref Des/Silkscreen Bottom")
		(1 "F.Mask" user "Board Geometry/Soldermask Top")
		(3 "B.Mask" user "Board Geometry/Soldermask Bottom")
		(17 "Dwgs.User" user "User.Drawings")
		(19 "Cmts.User" user "User.Comments")
		(21 "Eco1.User" user "User.Eco1")
		(23 "Eco2.User" user "User.Eco2")
		(25 "Edge.Cuts" user "Board Geometry/Outline")
		(27 "Margin" user)
		(31 "F.CrtYd" user "Package Geometry/Place Bound Top")
		(29 "B.CrtYd" user "Package Geometry/Place Bound Bottom")
		(35 "F.Fab" user "Ref Des/Assembly Top")
		(33 "B.Fab" user "Ref Des/Assembly Bottom")
	)
	(footprint ""
		(layer "F.Cu")
		(at 464.82 -258.826 90)
		(property "Reference" "C169"
			(at 0 0 90)
			(layer "F.SilkS")
			(hide yes)
			(effects
				(font
					(size 1.27 1.27)
				)
			)
		)
		(property "Value" "SCD033U25V2KX-GP"
			(at 1.1811 -2.7051 90)
			(unlocked yes)
			(layer "F.Fab")
			(hide yes)
			(effects
				(font
					(size 1.016 1.016)
					(thickness 0.1524)
				)
			)
		)
		(property "Device Type" "C402H22"
			(at 1.1811 -4.2291 90)
			(unlocked yes)
			(layer "F.Fab")
			(hide yes)
			(effects
				(font
					(size 1.016 1.016)
					(thickness 0.1524)
				)
			)
		)
		(duplicate_pad_numbers_are_jumpers no)
		(fp_rect
			(start -0.4318 0.9525)
			(end 0.4318 -0.9525)
			(stroke
				(width 0)
				(type default)
			)
			(fill no)
			(layer "F.CrtYd")
		)
		(fp_rect
			(start -0.4318 0.9525)
			(end 0.4318 -0.9525)
			(stroke
				(width 0)
				(type default)
			)
			(fill no)
			(layer "F.Fab")
		)
		(pad "1" smd custom
			(at 0 -0.4445 90)
			(size 0.1524 0.1524)
			(layers "F.Cu" "F.Mask" "F.Paste")
			(net "P12V_B")
			(options
				(clearance outline)
				(anchor circle)
			)
			(primitives
				(gr_poly
					(pts
						(arc
							(start 0.3048 -0.2032)
							(mid 0.275042 -0.275042)
							(end 0.2032 -0.3048)
						)
						(arc
							(start -0.2032 -0.3048)
							(mid -0.275042 -0.275042)
							(end -0.3048 -0.2032)
						)
						(arc
							(start -0.3048 0.2032)
							(mid -0.275042 0.275042)
							(end -0.2032 0.3048)
						)
						(arc
							(start 0.2032 0.3048)
							(mid 0.275042 0.275042)
							(end 0.3048 0.2032)
						)
					)
					(width 0)
					(fill yes)
				)
			)
		)
		(pad "2" smd custom
			(at 0 0.4445 90)
			(size 0.1524 0.1524)
			(layers "F.Cu" "F.Mask" "F.Paste")
			(net "SW_HDD_N10")
			(options
				(clearance outline)
				(anchor circle)
			)
			(primitives
				(gr_poly
					(pts
						(arc
							(start 0.3048 -0.2032)
							(mid 0.275042 -0.275042)
							(end 0.2032 -0.3048)
						)
						(arc
							(start -0.2032 -0.3048)
							(mid -0.275042 -0.275042)
							(end -0.3048 -0.2032)
						)
						(arc
							(start -0.3048 0.2032)
							(mid -0.275042 0.275042)
							(end -0.2032 0.3048)
						)
						(arc
							(start 0.2032 0.3048)
							(mid 0.275042 0.275042)
							(end 0.3048 0.2032)
						)
					)
					(width 0)
					(fill yes)
				)
			)
		)
	)
	(footprint ""
		(layer "F.Cu")
		(at 263.1059 -379.174756 -90)
		(property "Reference" "R1068"
			(at 0 0 270)
			(layer "F.SilkS")
			(hide yes)
			(effects
				(font
					(size 1.27 1.27)
				)
			)
		)
		(property "Value" "1KR2J-1-GP"
			(at 0.064008 -3.993896 270)
			(unlocked yes)
			(layer "F.Fab")
			(hide yes)
			(effects
				(font
					(size 1.016 1.016)
					(thickness 0.1524)
				)
			)
		)
		(property "Device Type" "R402H16"
			(at 0.064008 -5.517896 270)
			(unlocked yes)
			(layer "F.Fab")
			(hide yes)
			(effects
				(font
					(size 1.016 1.016)
					(thickness 0.1524)
				)
			)
		)
		(duplicate_pad_numbers_are_jumpers no)
		(fp_line
			(start -0.508 -0.9398)
			(end -0.508 0.9398)
			(stroke
				(width 0.1524)
				(type default)
			)
			(layer "F.SilkS")
		)
		(fp_line
			(start 0.508 -0.9398)
			(end -0.508 -0.9398)
			(stroke
				(width 0.1524)
				(type default)
			)
			(layer "F.SilkS")
		)
		(fp_rect
			(start -0.508 0.9398)
			(end 0.508 -0.9398)
			(stroke
				(width 0)
				(type default)
			)
			(fill no)
			(layer "F.CrtYd")
		)
		(fp_rect
			(start -0.508 0.9398)
			(end 0.508 -0.9398)
			(stroke
				(width 0)
				(type default)
			)
			(fill no)
			(layer "F.Fab")
		)
		(pad "1" smd custom
			(at 0 -0.4445 270)
			(size 0.1397 0.1397)
			(layers "F.Cu" "F.Mask" "F.Paste")
			(net "DRAWER_OUT_NET")
			(options
				(clearance outline)
				(anchor circle)
			)
			(primitives
				(gr_poly
					(pts
						(arc
							(start -0.1778 -0.2794)
							(mid -0.249642 -0.249642)
							(end -0.2794 -0.1778)
						)
						(arc
							(start -0.2794 0.1778)
							(mid -0.249642 0.249642)
							(end -0.1778 0.2794)
						)
						(arc
							(start 0.1778 0.2794)
							(mid 0.249642 0.249642)
							(end 0.2794 0.1778)
						)
						(arc
							(start 0.2794 -0.1778)
							(mid 0.249642 -0.249642)
							(end 0.1778 -0.2794)
						)
					)
					(width 0)
					(fill yes)
				)
			)
		)
		(pad "2" smd custom
			(at 0 0.4445 270)
			(size 0.1397 0.1397)
			(layers "F.Cu" "F.Mask" "F.Paste")
			(net "DRAWER_OUT_NET_B")
			(options
				(clearance outline)
				(anchor circle)
			)
			(primitives
				(gr_poly
					(pts
						(arc
							(start -0.1778 -0.2794)
							(mid -0.249642 -0.249642)
							(end -0.2794 -0.1778)
						)
						(arc
							(start -0.2794 0.1778)
							(mid -0.249642 0.249642)
							(end -0.1778 0.2794)
						)
						(arc
							(start 0.1778 0.2794)
							(mid 0.249642 0.249642)
							(end 0.2794 0.1778)
						)
						(arc
							(start 0.2794 -0.1778)
							(mid 0.249642 -0.249642)
							(end 0.1778 -0.2794)
						)
					)
					(width 0)
					(fill yes)
				)
			)
		)
	)
	(footprint ""
		(layer "F.Cu")
		(at 14.859 -260.858)
		(property "Reference" "Q192"
			(at 0 0 0)
			(layer "F.SilkS")
			(hide yes)
			(effects
				(font
					(size 1.27 1.27)
				)
			)
		)
		(property "Value" "AO4407AL-GP"
			(at -3.707384 -1.5367 0)
			(unlocked yes)
			(layer "F.Fab")
			(hide yes)
			(effects
				(font
					(size 1.016 1.016)
					(thickness 0.1524)
				)
			)
		)
		(property "Device Type" "SOIC8H69"
			(at -3.707384 -3.0607 0)
			(unlocked yes)
			(layer "F.Fab")
			(hide yes)
			(effects
				(font
					(size 1.016 1.016)
					(thickness 0.1524)
				)
			)
		)
		(duplicate_pad_numbers_are_jumpers no)
		(fp_line
			(start -2.7432 -1.4224)
			(end -2.7432 1.4224)
			(stroke
				(width 0.1524)
				(type default)
			)
			(layer "F.SilkS")
		)
		(fp_line
			(start -2.7432 1.4224)
			(end -2.6416 1.4224)
			(stroke
				(width 0.1524)
				(type default)
			)
			(layer "F.SilkS")
		)
		(fp_line
			(start -2.7432 1.4224)
			(end 2.1336 1.4224)
			(stroke
				(width 0.1524)
				(type default)
			)
			(layer "F.SilkS")
		)
		(fp_line
			(start -2.7178 -0.508)
			(end -2.1844 -0.0508)
			(stroke
				(width 0.1524)
				(type default)
			)
			(layer "F.SilkS")
		)
		(fp_line
			(start -2.6289 3.4417)
			(end -2.6289 1.4732)
			(stroke
				(width 0.381)
				(type default)
			)
			(layer "F.SilkS")
		)
		(fp_line
			(start -2.1844 -0.0508)
			(end -2.7178 0.508)
			(stroke
				(width 0.1524)
				(type default)
			)
			(layer "F.SilkS")
		)
		(fp_line
			(start 2.1336 -1.4224)
			(end -2.7432 -1.4224)
			(stroke
				(width 0.1524)
				(type default)
			)
			(layer "F.SilkS")
		)
		(fp_line
			(start 2.1336 1.4224)
			(end 2.1336 -1.4224)
			(stroke
				(width 0.1524)
				(type default)
			)
			(layer "F.SilkS")
		)
		(fp_poly
			(pts
				(xy -2.2098 -1.4224) (xy -2.2098 1.4224) (xy 2.2098 1.4224) (xy 2.2098 -1.4224)
			)
			(stroke
				(width 0)
				(type default)
			)
			(fill yes)
			(layer "F.SilkS")
		)
		(fp_rect
			(start -2.450084 2.999994)
			(end 2.450084 -2.999994)
			(stroke
				(width 0)
				(type default)
			)
			(fill no)
			(layer "F.CrtYd")
		)
		(fp_poly
			(pts
				(xy -2.8194 3.6322) (xy -2.8194 -3.6322) (xy 2.8194 -3.6322) (xy 2.8194 1.18364) (xy 2.450084 1.18364)
				(xy 2.450084 -2.999994) (xy -2.450084 -2.999994) (xy -2.450084 2.999994) (xy 2.450084 2.999994)
				(xy 2.450084 1.18618) (xy 2.8194 1.18618) (xy 2.8194 3.6322)
			)
			(stroke
				(width 0)
				(type default)
			)
			(fill no)
			(layer "F.CrtYd")
		)
		(fp_rect
			(start -2.8194 3.6322)
			(end 2.8194 -3.6322)
			(stroke
				(width 0)
				(type default)
			)
			(fill no)
			(layer "F.Fab")
		)
		(pad "1" smd rect
			(at -1.905 2.54)
			(size 0.635 1.651)
			(layers "F.Cu" "F.Mask" "F.Paste")
			(net "P12V_B")
		)
		(pad "2" smd rect
			(at -0.635 2.54)
			(size 0.635 1.651)
			(layers "F.Cu" "F.Mask" "F.Paste")
			(net "P12V_B")
		)
		(pad "3" smd rect
			(at 0.635 2.54)
			(size 0.635 1.651)
			(layers "F.Cu" "F.Mask" "F.Paste")
			(net "P12V_B")
		)
		(pad "4" smd rect
			(at 1.905 2.54)
			(size 0.635 1.651)
			(layers "F.Cu" "F.Mask" "F.Paste")
			(net "SW_HDD_N0")
		)
		(pad "5" smd rect
			(at 1.905 -2.54)
			(size 0.635 1.651)
			(layers "F.Cu" "F.Mask" "F.Paste")
			(net "P12V_HDD0")
		)
		(pad "6" smd rect
			(at 0.635 -2.54)
			(size 0.635 1.651)
			(layers "F.Cu" "F.Mask" "F.Paste")
			(net "P12V_HDD0")
		)
		(pad "7" smd rect
			(at -0.635 -2.54)
			(size 0.635 1.651)
			(layers "F.Cu" "F.Mask" "F.Paste")
			(net "P12V_HDD0")
		)
		(pad "8" smd rect
			(at -1.905 -2.54)
			(size 0.635 1.651)
			(layers "F.Cu" "F.Mask" "F.Paste")
			(net "P12V_HDD0")
		)
	)
	(footprint ""
		(layer "F.Cu")
		(at 286.639 -328.0918 -90)
		(property "Reference" "R93"
			(at 0 0 270)
			(layer "F.SilkS")
			(hide yes)
			(effects
				(font
					(size 1.27 1.27)
				)
			)
		)
		(property "Value" "4K7R2F-GP"
			(at 0.064008 -3.993896 270)
			(unlocked yes)
			(layer "F.Fab")
			(hide yes)
			(effects
				(font
					(size 1.016 1.016)
					(thickness 0.1524)
				)
			)
		)
		(property "Device Type" "R402H16"
			(at 0.064008 -5.517896 270)
			(unlocked yes)
			(layer "F.Fab")
			(hide yes)
			(effects
				(font
					(size 1.016 1.016)
					(thickness 0.1524)
				)
			)
		)
		(duplicate_pad_numbers_are_jumpers no)
		(fp_line
			(start -0.508 -0.9398)
			(end -0.508 0.9398)
			(stroke
				(width 0.1524)
				(type default)
			)
			(layer "F.SilkS")
		)
		(fp_line
			(start 0.508 -0.9398)
			(end -0.508 -0.9398)
			(stroke
				(width 0.1524)
				(type default)
			)
			(layer "F.SilkS")
		)
		(fp_rect
			(start -0.508 0.9398)
			(end 0.508 -0.9398)
			(stroke
				(width 0)
				(type default)
			)
			(fill no)
			(layer "F.CrtYd")
		)
		(fp_rect
			(start -0.508 0.9398)
			(end 0.508 -0.9398)
			(stroke
				(width 0)
				(type default)
			)
			(fill no)
			(layer "F.Fab")
		)
		(pad "1" smd custom
			(at 0 -0.4445 270)
			(size 0.1397 0.1397)
			(layers "F.Cu" "F.Mask" "F.Paste")
			(net "P3V3_IN")
			(options
				(clearance outline)
				(anchor circle)
			)
			(primitives
				(gr_poly
					(pts
						(arc
							(start -0.1778 -0.2794)
							(mid -0.249642 -0.249642)
							(end -0.2794 -0.1778)
						)
						(arc
							(start -0.2794 0.1778)
							(mid -0.249642 0.249642)
							(end -0.1778 0.2794)
						)
						(arc
							(start 0.1778 0.2794)
							(mid 0.249642 0.249642)
							(end 0.2794 0.1778)
						)
						(arc
							(start 0.2794 -0.1778)
							(mid 0.249642 -0.249642)
							(end 0.1778 -0.2794)
						)
					)
					(width 0)
					(fill yes)
				)
			)
		)
		(pad "2" smd custom
			(at 0 0.4445 270)
			(size 0.1397 0.1397)
			(layers "F.Cu" "F.Mask" "F.Paste")
			(net "PWM_OUT_FAN3")
			(options
				(clearance outline)
				(anchor circle)
			)
			(primitives
				(gr_poly
					(pts
						(arc
							(start -0.1778 -0.2794)
							(mid -0.249642 -0.249642)
							(end -0.2794 -0.1778)
						)
						(arc
							(start -0.2794 0.1778)
							(mid -0.249642 0.249642)
							(end -0.1778 0.2794)
						)
						(arc
							(start 0.1778 0.2794)
							(mid 0.249642 0.249642)
							(end 0.2794 0.1778)
						)
						(arc
							(start 0.2794 -0.1778)
							(mid 0.249642 -0.249642)
							(end 0.1778 -0.2794)
						)
					)
					(width 0)
					(fill yes)
				)
			)
		)
	)
	(footprint ""
		(layer "F.Cu")
		(at 79.883 -254.127 -90)
		(property "Reference" "C64"
			(at 0 0 270)
			(layer "F.SilkS")
			(hide yes)
			(effects
				(font
					(size 1.27 1.27)
				)
			)
		)
		(property "Value" "SCD033U25V2KX-GP"
			(at 1.1811 -2.7051 270)
			(unlocked yes)
			(layer "F.Fab")
			(hide yes)
			(effects
				(font
					(size 1.016 1.016)
					(thickness 0.1524)
				)
			)
		)
		(property "Device Type" "C402H22"
			(at 1.1811 -4.2291 270)
			(unlocked yes)
			(layer "F.Fab")
			(hide yes)
			(effects
				(font
					(size 1.016 1.016)
					(thickness 0.1524)
				)
			)
		)
		(duplicate_pad_numbers_are_jumpers no)
		(fp_rect
			(start -0.4318 0.9525)
			(end 0.4318 -0.9525)
			(stroke
				(width 0)
				(type default)
			)
			(fill no)
			(layer "F.CrtYd")
		)
		(fp_rect
			(start -0.4318 0.9525)
			(end 0.4318 -0.9525)
			(stroke
				(width 0)
				(type default)
			)
			(fill no)
			(layer "F.Fab")
		)
		(pad "1" smd custom
			(at 0 -0.4445 270)
			(size 0.1524 0.1524)
			(layers "F.Cu" "F.Mask" "F.Paste")
			(net "SW_HDD_P2")
			(options
				(clearance outline)
				(anchor circle)
			)
			(primitives
				(gr_poly
					(pts
						(arc
							(start 0.3048 -0.2032)
							(mid 0.275042 -0.275042)
							(end 0.2032 -0.3048)
						)
						(arc
							(start -0.2032 -0.3048)
							(mid -0.275042 -0.275042)
							(end -0.3048 -0.2032)
						)
						(arc
							(start -0.3048 0.2032)
							(mid -0.275042 0.275042)
							(end -0.2032 0.3048)
						)
						(arc
							(start 0.2032 0.3048)
							(mid 0.275042 0.275042)
							(end 0.3048 0.2032)
						)
					)
					(width 0)
					(fill yes)
				)
			)
		)
		(pad "2" smd custom
			(at 0 0.4445 270)
			(size 0.1524 0.1524)
			(layers "F.Cu" "F.Mask" "F.Paste")
			(net "GND")
			(options
				(clearance outline)
				(anchor circle)
			)
			(primitives
				(gr_poly
					(pts
						(arc
							(start 0.3048 -0.2032)
							(mid 0.275042 -0.275042)
							(end 0.2032 -0.3048)
						)
						(arc
							(start -0.2032 -0.3048)
							(mid -0.275042 -0.275042)
							(end -0.3048 -0.2032)
						)
						(arc
							(start -0.3048 0.2032)
							(mid -0.275042 0.275042)
							(end -0.2032 0.3048)
						)
						(arc
							(start 0.2032 0.3048)
							(mid 0.275042 0.275042)
							(end 0.3048 0.2032)
						)
					)
					(width 0)
					(fill yes)
				)
			)
		)
	)
	(footprint ""
		(layer "F.Cu")
		(at 327.373996 -365.379 -90)
		(property "Reference" "R950"
			(at 0 0 270)
			(layer "F.SilkS")
			(hide yes)
			(effects
				(font
					(size 1.27 1.27)
				)
			)
		)
		(property "Value" "27KR3F-GP"
			(at -0.0254 -2.5146 270)
			(unlocked yes)
			(layer "F.Fab")
			(hide yes)
			(effects
				(font
					(size 1.016 1.016)
					(thickness 0.1524)
				)
			)
		)
		(property "Device Type" "R603H22"
			(at -0.0254 -4.0386 270)
			(unlocked yes)
			(layer "F.Fab")
			(hide yes)
			(effects
				(font
					(size 1.016 1.016)
					(thickness 0.1524)
				)
			)
		)
		(duplicate_pad_numbers_are_jumpers no)
		(fp_line
			(start -0.4826 0)
			(end -0.2032 0)
			(stroke
				(width 0.2032)
				(type default)
			)
			(layer "F.SilkS")
		)
		(fp_line
			(start 0.2032 0)
			(end 0.4826 0)
			(stroke
				(width 0.2032)
				(type default)
			)
			(layer "F.SilkS")
		)
		(fp_rect
			(start -0.5842 1.3335)
			(end 0.5842 -1.3335)
			(stroke
				(width 0)
				(type default)
			)
			(fill no)
			(layer "F.CrtYd")
		)
		(fp_rect
			(start -0.5842 1.3335)
			(end 0.5842 -1.3335)
			(stroke
				(width 0)
				(type default)
			)
			(fill no)
			(layer "F.Fab")
		)
		(pad "1" smd custom
			(at 0 -0.762 270)
			(size 0.2159 0.2159)
			(layers "F.Cu" "F.Mask" "F.Paste")
			(net "FAN_2_TACH1")
			(options
				(clearance outline)
				(anchor circle)
			)
			(primitives
				(gr_poly
					(pts
						(arc
							(start -0.3302 -0.4318)
							(mid -0.402042 -0.402042)
							(end -0.4318 -0.3302)
						)
						(arc
							(start -0.4318 0.3302)
							(mid -0.402042 0.402042)
							(end -0.3302 0.4318)
						)
						(arc
							(start 0.3302 0.4318)
							(mid 0.402042 0.402042)
							(end 0.4318 0.3302)
						)
						(arc
							(start 0.4318 -0.3302)
							(mid 0.402042 -0.402042)
							(end 0.3302 -0.4318)
						)
					)
					(width 0)
					(fill yes)
				)
			)
		)
		(pad "2" smd custom
			(at 0 0.762 270)
			(size 0.2159 0.2159)
			(layers "F.Cu" "F.Mask" "F.Paste")
			(net "FANTACH_F2")
			(options
				(clearance outline)
				(anchor circle)
			)
			(primitives
				(gr_poly
					(pts
						(arc
							(start -0.3302 -0.4318)
							(mid -0.402042 -0.402042)
							(end -0.4318 -0.3302)
						)
						(arc
							(start -0.4318 0.3302)
							(mid -0.402042 0.402042)
							(end -0.3302 0.4318)
						)
						(arc
							(start 0.3302 0.4318)
							(mid 0.402042 0.402042)
							(end 0.4318 0.3302)
						)
						(arc
							(start 0.4318 -0.3302)
							(mid 0.402042 -0.402042)
							(end 0.3302 -0.4318)
						)
					)
					(width 0)
					(fill yes)
				)
			)
		)
	)
	(footprint ""
		(layer "F.Cu")
		(at 269.269972 -351.304606)
		(property "Reference" "R1055"
			(at 0 0 0)
			(layer "F.SilkS")
			(hide yes)
			(effects
				(font
					(size 1.27 1.27)
				)
			)
		)
		(property "Value" "1KR2J-1-GP"
			(at 0.064008 -3.993896 0)
			(unlocked yes)
			(layer "F.Fab")
			(hide yes)
			(effects
				(font
					(size 1.016 1.016)
					(thickness 0.1524)
				)
			)
		)
		(property "Device Type" "R402H16"
			(at 0.064008 -5.517896 0)
			(unlocked yes)
			(layer "F.Fab")
			(hide yes)
			(effects
				(font
					(size 1.016 1.016)
					(thickness 0.1524)
				)
			)
		)
		(duplicate_pad_numbers_are_jumpers no)
		(fp_line
			(start -0.508 -0.9398)
			(end -0.508 0.9398)
			(stroke
				(width 0.1524)
				(type default)
			)
			(layer "F.SilkS")
		)
		(fp_line
			(start 0.508 -0.9398)
			(end -0.508 -0.9398)
			(stroke
				(width 0.1524)
				(type default)
			)
			(layer "F.SilkS")
		)
		(fp_rect
			(start -0.508 0.9398)
			(end 0.508 -0.9398)
			(stroke
				(width 0)
				(type default)
			)
			(fill no)
			(layer "F.CrtYd")
		)
		(fp_rect
			(start -0.508 0.9398)
			(end 0.508 -0.9398)
			(stroke
				(width 0)
				(type default)
			)
			(fill no)
			(layer "F.Fab")
		)
		(pad "1" smd custom
			(at 0 -0.4445)
			(size 0.1397 0.1397)
			(layers "F.Cu" "F.Mask" "F.Paste")
			(net "MB3_CM_VOUT_R")
			(options
				(clearance outline)
				(anchor circle)
			)
			(primitives
				(gr_poly
					(pts
						(arc
							(start -0.1778 -0.2794)
							(mid -0.249642 -0.249642)
							(end -0.2794 -0.1778)
						)
						(arc
							(start -0.2794 0.1778)
							(mid -0.249642 0.249642)
							(end -0.1778 0.2794)
						)
						(arc
							(start 0.1778 0.2794)
							(mid 0.249642 0.249642)
							(end 0.2794 0.1778)
						)
						(arc
							(start 0.2794 -0.1778)
							(mid 0.249642 -0.249642)
							(end 0.1778 -0.2794)
						)
					)
					(width 0)
					(fill yes)
				)
			)
		)
		(pad "2" smd custom
			(at 0 0.4445)
			(size 0.1397 0.1397)
			(layers "F.Cu" "F.Mask" "F.Paste")
			(net "P12V_B")
			(options
				(clearance outline)
				(anchor circle)
			)
			(primitives
				(gr_poly
					(pts
						(arc
							(start -0.1778 -0.2794)
							(mid -0.249642 -0.249642)
							(end -0.2794 -0.1778)
						)
						(arc
							(start -0.2794 0.1778)
							(mid -0.249642 0.249642)
							(end -0.1778 0.2794)
						)
						(arc
							(start 0.1778 0.2794)
							(mid 0.249642 0.249642)
							(end 0.2794 0.1778)
						)
						(arc
							(start 0.2794 -0.1778)
							(mid 0.249642 -0.249642)
							(end 0.1778 -0.2794)
						)
					)
					(width 0)
					(fill yes)
				)
			)
		)
	)
)
